# TIMECARD (Time Appliance Project (Time Card)) — schematic netlist excerpt (pin names and nets, part order shuffled) for the footprints in the layout excerpt that follows; sources: Cadence DE-HDL packaged netlist, KiCad conversion of R4006-B0001-02_R01.brd

C166  CAPACITOR  0.1UF 10V 10%  pkg SMC_0402R_H022  page 14 : \1\ = XP1R0V_FPGA_VCCINT ; \2\ = SG
C170  CAPACITOR  4.7UF 6.3V 20%  pkg SMC_0402R_H026  page 14 : \1\ = XP3R3V_FPGA ; \2\ = SG

(kicad_pcb
	(version 20260206)
	(generator "pcbnew")
	(generator_version "10.0")
	(general
		(thickness 1.6)
		(legacy_teardrops no)
	)
	(paper "A4")
	(title_block
		(title "timecard-production-celestica-r4006 — R4006-B0001-02_R01.brd")
		(comment 1 "Time Appliance Project (Time Card) / footprints 781-782 of 1113")
	)
	(layers
		(0 "F.Cu" signal "TOP")
		(4 "In1.Cu" signal "L02_GND1")
		(6 "In2.Cu" signal "L03_SIG1")
		(8 "In3.Cu" signal "L04_GND2")
		(10 "In4.Cu" signal "L05_VCC1")
		(12 "In5.Cu" signal "L06_VCC2")
		(14 "In6.Cu" signal "L07_GND3")
		(16 "In7.Cu" signal "L08_SIG2")
		(18 "In8.Cu" signal "L09_GND4")
		(2 "B.Cu" signal "BOTTOM")
		(9 "F.Adhes" user "F.Adhesive")
		(11 "B.Adhes" user "B.Adhesive")
		(13 "F.Paste" user "Package Geometry/Pastemask Top")
		(15 "B.Paste" user "Package Geometry/Pastemask Bottom")
		(5 "F.SilkS" user "Ref Des/Silkscreen Top")
		(7 "B.SilkS" user "Ref Des/Silkscreen Bottom")
		(1 "F.Mask" user "Board Geometry/Soldermask Top")
		(3 "B.Mask" user "Board Geometry/Soldermask Bottom")
		(17 "Dwgs.User" user "User.Drawings")
		(19 "Cmts.User" user "User.Comments")
		(21 "Eco1.User" user "User.Eco1")
		(23 "Eco2.User" user "User.Eco2")
		(25 "Edge.Cuts" user "Board Geometry/Outline")
		(27 "Margin" user)
		(31 "F.CrtYd" user "Package Geometry/Place Bound Top")
		(29 "B.CrtYd" user "Package Geometry/Place Bound Bottom")
		(35 "F.Fab" user "Ref Des/Assembly Top")
		(33 "B.Fab" user "Ref Des/Assembly Bottom")
	)
	(footprint ""
		(layer "B.Cu")
		(at 107.84713 -41.32326 -90)
		(property "Reference" "C166"
			(at 1.016 41.38422 270)
			(unlocked yes)
			(layer "B.SilkS")
			(effects
				(font
					(size 0.635 0.4064)
					(thickness 0.1524)
				)
				(justify mirror)
			)
		)
		(property "Value" "VAL*"
			(at 0 3.718306 270)
			(unlocked yes)
			(layer "B.Fab")
			(hide yes)
			(effects
				(font
					(size 0.7874 0.5842)
					(thickness 0.127)
				)
				(justify mirror)
			)
		)
		(property "Device Type" "CAPACITOR-G105-0B104-CK,0.1UF,A"
			(at 0 1.432306 270)
			(unlocked yes)
			(layer "B.Fab")
			(hide yes)
			(effects
				(font
					(size 0.7874 0.5842)
					(thickness 0.127)
				)
				(justify mirror)
			)
		)
		(property "User Part Number" "PARTNUM*"
			(at 0 2.575306 270)
			(unlocked yes)
			(layer "Cmts.User")
			(hide yes)
			(effects
				(font
					(size 0.7874 0.5842)
					(thickness 0.127)
				)
				(justify mirror)
			)
		)
		(property "Tolerance" "TOL*"
			(at 0 4.861306 270)
			(unlocked yes)
			(layer "Cmts.User")
			(hide yes)
			(effects
				(font
					(size 0.7874 0.5842)
					(thickness 0.127)
				)
				(justify mirror)
			)
		)
		(duplicate_pad_numbers_are_jumpers no)
		(fp_line
			(start -0.970026 0.4699)
			(end 0.970026 0.4699)
			(stroke
				(width 0.1)
				(type default)
			)
			(layer "B.SilkS")
		)
		(fp_line
			(start 0.970026 0.4699)
			(end 0.970026 -0.4699)
			(stroke
				(width 0.1)
				(type default)
			)
			(layer "B.SilkS")
		)
		(fp_line
			(start -0.970026 -0.4699)
			(end -0.970026 0.4699)
			(stroke
				(width 0.1)
				(type default)
			)
			(layer "B.SilkS")
		)
		(fp_line
			(start 0.970026 -0.4699)
			(end -0.970026 -0.4699)
			(stroke
				(width 0.1)
				(type default)
			)
			(layer "B.SilkS")
		)
		(fp_poly
			(pts
				(xy 0.970026 0.4699) (xy -0.970026 0.4699) (xy -0.970026 -0.4699) (xy 0.970026 -0.4699)
			)
			(stroke
				(width 0)
				(type default)
			)
			(fill no)
			(layer "B.CrtYd")
		)
		(fp_line
			(start -0.508 0.3048)
			(end 0.508 0.3048)
			(stroke
				(width 0.1)
				(type default)
			)
			(layer "B.Fab")
		)
		(fp_line
			(start 0.508 0.3048)
			(end 0.508 -0.3048)
			(stroke
				(width 0.1)
				(type default)
			)
			(layer "B.Fab")
		)
		(fp_line
			(start -0.508 -0.3048)
			(end -0.508 0.3048)
			(stroke
				(width 0.1)
				(type default)
			)
			(layer "B.Fab")
		)
		(fp_line
			(start 0.508 -0.3048)
			(end -0.508 -0.3048)
			(stroke
				(width 0.1)
				(type default)
			)
			(layer "B.Fab")
		)
		(pad "1" smd circle
			(at 0.500126 0 90)
			(size 0.635 0.635)
			(layers "B.Cu" "B.Mask" "B.Paste")
			(net "XP1R0V_FPGA_VCCINT")
		)
		(pad "2" smd circle
			(at -0.500126 0 90)
			(size 0.635 0.635)
			(layers "B.Cu" "B.Mask" "B.Paste")
			(net "SG")
		)
	)
	(footprint ""
		(layer "B.Cu")
		(at 102.84714 -49.323244 -90)
		(property "Reference" "C170"
			(at -2.111756 0.26289 270)
			(unlocked yes)
			(layer "B.SilkS")
			(effects
				(font
					(size 0.635 0.4064)
					(thickness 0.1524)
				)
				(justify mirror)
			)
		)
		(property "Value" "VAL*"
			(at 0 3.718306 270)
			(unlocked yes)
			(layer "B.Fab")
			(hide yes)
			(effects
				(font
					(size 0.7874 0.5842)
					(thickness 0.127)
				)
				(justify mirror)
			)
		)
		(property "Device Type" "CAPACITOR-G105-0F475-BM,4.7UF,A"
			(at 0 1.432306 270)
			(unlocked yes)
			(layer "B.Fab")
			(hide yes)
			(effects
				(font
					(size 0.7874 0.5842)
					(thickness 0.127)
				)
				(justify mirror)
			)
		)
		(property "User Part Number" "PARTNUM*"
			(at 0 2.575306 270)
			(unlocked yes)
			(layer "Cmts.User")
			(hide yes)
			(effects
				(font
					(size 0.7874 0.5842)
					(thickness 0.127)
				)
				(justify mirror)
			)
		)
		(property "Tolerance" "TOL*"
			(at 0 4.861306 270)
			(unlocked yes)
			(layer "Cmts.User")
			(hide yes)
			(effects
				(font
					(size 0.7874 0.5842)
					(thickness 0.127)
				)
				(justify mirror)
			)
		)
		(duplicate_pad_numbers_are_jumpers no)
		(fp_line
			(start -0.970026 0.4699)
			(end 0.970026 0.4699)
			(stroke
				(width 0.1)
				(type default)
			)
			(layer "B.SilkS")
		)
		(fp_line
			(start 0.970026 0.4699)
			(end 0.970026 -0.4699)
			(stroke
				(width 0.1)
				(type default)
			)
			(layer "B.SilkS")
		)
		(fp_line
			(start -0.970026 -0.4699)
			(end -0.970026 0.4699)
			(stroke
				(width 0.1)
				(type default)
			)
			(layer "B.SilkS")
		)
		(fp_line
			(start 0.970026 -0.4699)
			(end -0.970026 -0.4699)
			(stroke
				(width 0.1)
				(type default)
			)
			(layer "B.SilkS")
		)
		(fp_poly
			(pts
				(xy 0.970026 0.4699) (xy -0.970026 0.4699) (xy -0.970026 -0.4699) (xy 0.970026 -0.4699)
			)
			(stroke
				(width 0)
				(type default)
			)
			(fill no)
			(layer "B.CrtYd")
		)
		(fp_line
			(start -0.508 0.3048)
			(end 0.508 0.3048)
			(stroke
				(width 0.1)
				(type default)
			)
			(layer "B.Fab")
		)
		(fp_line
			(start 0.508 0.3048)
			(end 0.508 -0.3048)
			(stroke
				(width 0.1)
				(type default)
			)
			(layer "B.Fab")
		)
		(fp_line
			(start -0.508 -0.3048)
			(end -0.508 0.3048)
			(stroke
				(width 0.1)
				(type default)
			)
			(layer "B.Fab")
		)
		(fp_line
			(start 0.508 -0.3048)
			(end -0.508 -0.3048)
			(stroke
				(width 0.1)
				(type default)
			)
			(layer "B.Fab")
		)
		(pad "1" smd circle
			(at 0.500126 0 90)
			(size 0.635 0.635)
			(layers "B.Cu" "B.Mask" "B.Paste")
			(net "XP3R3V_FPGA")
		)
		(pad "2" smd circle
			(at -0.500126 0 90)
			(size 0.635 0.635)
			(layers "B.Cu" "B.Mask" "B.Paste")
			(net "SG")
		)
	)
)
